(kicad_pcb
	(version 20260206)
	(generator "pcbnew")
	(generator_version "10.0")
	(general
		(thickness 1.6)
		(legacy_teardrops no)
	)
	(paper "A4")
	(title_block
		(title "01162023_DA0F0TEBIF0_F0T_Expander_BD_F_brd_V02_OCP.brd")
		(comment 1 "Grand Teton / footprints 6477-6482 of 9728")
	)
	(layers
		(0 "F.Cu" signal "TOP")
		(4 "In1.Cu" signal "GND")
		(6 "In2.Cu" signal "VCC")
		(8 "In3.Cu" signal "VCC1")
		(10 "In4.Cu" signal "GND1")
		(12 "In5.Cu" signal "IN1")
		(14 "In6.Cu" signal "GND2")
		(16 "In7.Cu" signal "IN2")
		(18 "In8.Cu" signal "GND3")
		(20 "In9.Cu" signal "IN3")
		(22 "In10.Cu" signal "GND4")
		(24 "In11.Cu" signal "IN4")
		(26 "In12.Cu" signal "GND5")
		(28 "In13.Cu" signal "IN5")
		(30 "In14.Cu" signal "GND6")
		(32 "In15.Cu" signal "IN6")
		(34 "In16.Cu" signal "GND7")
		(2 "B.Cu" signal "BOTTOM")
		(9 "F.Adhes" user "F.Adhesive")
		(11 "B.Adhes" user "B.Adhesive")
		(13 "F.Paste" user "Package Geometry/Pastemask Top")
		(15 "B.Paste" user "Package Geometry/Pastemask Bottom")
		(5 "F.SilkS" user "Ref Des/Silkscreen Top")
		(7 "B.SilkS" user "Ref Des/Silkscreen Bottom")
		(1 "F.Mask" user "Board Geometry/Soldermask Top")
		(3 "B.Mask" user "Board Geometry/Soldermask Bottom")
		(17 "Dwgs.User" user "User.Drawings")
		(19 "Cmts.User" user "User.Comments")
		(21 "Eco1.User" user "User.Eco1")
		(23 "Eco2.User" user "User.Eco2")
		(25 "Edge.Cuts" user "Board Geometry/Outline")
		(27 "Margin" user)
		(31 "F.CrtYd" user "Package Geometry/Place Bound Top")
		(29 "B.CrtYd" user "Package Geometry/Place Bound Bottom")
		(35 "F.Fab" user "Ref Des/Assembly Top")
		(33 "B.Fab" user "Ref Des/Assembly Bottom")
	)
	(footprint ""
		(layer "F.Cu")
		(at 142.343886 -46.90491)
		(property "Reference" "R552"
			(at 0 0 0)
			(layer "F.SilkS")
			(hide yes)
			(effects
				(font
					(size 1.27 1.27)
				)
			)
		)
		(property "Value" ""
			(at 0 0 0)
			(layer "F.Fab")
			(effects
				(font
					(size 1.27 1.27)
				)
			)
		)
		(duplicate_pad_numbers_are_jumpers no)
		(fp_line
			(start -0.7874 -0.4064)
			(end 0.7874 -0.4064)
			(stroke
				(width 0.1524)
				(type default)
			)
			(layer "F.SilkS")
		)
		(fp_line
			(start -0.7874 0.4064)
			(end -0.7874 -0.4064)
			(stroke
				(width 0.1524)
				(type default)
			)
			(layer "F.SilkS")
		)
		(fp_line
			(start 0.7874 -0.4064)
			(end 0.7874 0.4064)
			(stroke
				(width 0.1524)
				(type default)
			)
			(layer "F.SilkS")
		)
		(fp_line
			(start 0.7874 0.4064)
			(end -0.7874 0.4064)
			(stroke
				(width 0.1524)
				(type default)
			)
			(layer "F.SilkS")
		)
		(fp_line
			(start -0.67945 -0.305054)
			(end -0.12065 -0.305054)
			(stroke
				(width 0.1)
				(type default)
			)
			(layer "F.Fab")
		)
		(fp_line
			(start -0.67945 0.3048)
			(end -0.67945 -0.305054)
			(stroke
				(width 0.1)
				(type default)
			)
			(layer "F.Fab")
		)
		(fp_line
			(start -0.12065 -0.305054)
			(end -0.12065 -0.2794)
			(stroke
				(width 0.1)
				(type default)
			)
			(layer "F.Fab")
		)
		(fp_line
			(start -0.12065 -0.2794)
			(end 0.12065 -0.2794)
			(stroke
				(width 0.1)
				(type default)
			)
			(layer "F.Fab")
		)
		(fp_line
			(start -0.12065 0.2794)
			(end -0.12065 0.3048)
			(stroke
				(width 0.1)
				(type default)
			)
			(layer "F.Fab")
		)
		(fp_line
			(start -0.12065 0.3048)
			(end -0.67945 0.3048)
			(stroke
				(width 0.1)
				(type default)
			)
			(layer "F.Fab")
		)
		(fp_line
			(start 0.120396 0.2794)
			(end -0.12065 0.2794)
			(stroke
				(width 0.1)
				(type default)
			)
			(layer "F.Fab")
		)
		(fp_line
			(start 0.120396 0.3048)
			(end 0.120396 0.2794)
			(stroke
				(width 0.1)
				(type default)
			)
			(layer "F.Fab")
		)
		(fp_line
			(start 0.12065 -0.3048)
			(end 0.67945 -0.3048)
			(stroke
				(width 0.1)
				(type default)
			)
			(layer "F.Fab")
		)
		(fp_line
			(start 0.12065 -0.2794)
			(end 0.12065 -0.3048)
			(stroke
				(width 0.1)
				(type default)
			)
			(layer "F.Fab")
		)
		(fp_line
			(start 0.67945 -0.3048)
			(end 0.67945 0.3048)
			(stroke
				(width 0.1)
				(type default)
			)
			(layer "F.Fab")
		)
		(fp_line
			(start 0.67945 0.3048)
			(end 0.120396 0.3048)
			(stroke
				(width 0.1)
				(type default)
			)
			(layer "F.Fab")
		)
		(pad "1" smd circle
			(at -0.40005 0)
			(size 0 0)
			(layers "F.Cu" "F.Mask" "F.Paste")
			(net "SSD4_ADC_ALERT_N")
		)
		(pad "2" smd circle
			(at 0.40005 0)
			(size 0 0)
			(layers "F.Cu" "F.Mask" "F.Paste")
			(net "SSD_0_7_ADC_ALERT_N")
		)
	)
	(footprint ""
		(layer "F.Cu")
		(at 345.76131 -261.687564 180)
		(property "Reference" "PR133"
			(at 0 0 180)
			(layer "F.SilkS")
			(hide yes)
			(effects
				(font
					(size 1.27 1.27)
				)
			)
		)
		(property "Value" ""
			(at 0 0 180)
			(layer "F.Fab")
			(effects
				(font
					(size 1.27 1.27)
				)
			)
		)
		(duplicate_pad_numbers_are_jumpers no)
		(fp_line
			(start 0.7874 0.4064)
			(end -0.7874 0.4064)
			(stroke
				(width 0.1524)
				(type default)
			)
			(layer "F.SilkS")
		)
		(fp_line
			(start 0.7874 -0.4064)
			(end 0.7874 0.4064)
			(stroke
				(width 0.1524)
				(type default)
			)
			(layer "F.SilkS")
		)
		(fp_line
			(start -0.7874 0.4064)
			(end -0.7874 -0.4064)
			(stroke
				(width 0.1524)
				(type default)
			)
			(layer "F.SilkS")
		)
		(fp_line
			(start -0.7874 -0.4064)
			(end 0.7874 -0.4064)
			(stroke
				(width 0.1524)
				(type default)
			)
			(layer "F.SilkS")
		)
		(fp_line
			(start 0.67945 0.3048)
			(end 0.120396 0.3048)
			(stroke
				(width 0.1)
				(type default)
			)
			(layer "F.Fab")
		)
		(fp_line
			(start 0.67945 -0.3048)
			(end 0.67945 0.3048)
			(stroke
				(width 0.1)
				(type default)
			)
			(layer "F.Fab")
		)
		(fp_line
			(start 0.12065 -0.2794)
			(end 0.12065 -0.3048)
			(stroke
				(width 0.1)
				(type default)
			)
			(layer "F.Fab")
		)
		(fp_line
			(start 0.12065 -0.3048)
			(end 0.67945 -0.3048)
			(stroke
				(width 0.1)
				(type default)
			)
			(layer "F.Fab")
		)
		(fp_line
			(start 0.120396 0.3048)
			(end 0.120396 0.2794)
			(stroke
				(width 0.1)
				(type default)
			)
			(layer "F.Fab")
		)
		(fp_line
			(start 0.120396 0.2794)
			(end -0.12065 0.2794)
			(stroke
				(width 0.1)
				(type default)
			)
			(layer "F.Fab")
		)
		(fp_line
			(start -0.12065 0.3048)
			(end -0.67945 0.3048)
			(stroke
				(width 0.1)
				(type default)
			)
			(layer "F.Fab")
		)
		(fp_line
			(start -0.12065 0.2794)
			(end -0.12065 0.3048)
			(stroke
				(width 0.1)
				(type default)
			)
			(layer "F.Fab")
		)
		(fp_line
			(start -0.12065 -0.2794)
			(end 0.12065 -0.2794)
			(stroke
				(width 0.1)
				(type default)
			)
			(layer "F.Fab")
		)
		(fp_line
			(start -0.12065 -0.305054)
			(end -0.12065 -0.2794)
			(stroke
				(width 0.1)
				(type default)
			)
			(layer "F.Fab")
		)
		(fp_line
			(start -0.67945 0.3048)
			(end -0.67945 -0.305054)
			(stroke
				(width 0.1)
				(type default)
			)
			(layer "F.Fab")
		)
		(fp_line
			(start -0.67945 -0.305054)
			(end -0.12065 -0.305054)
			(stroke
				(width 0.1)
				(type default)
			)
			(layer "F.Fab")
		)
		(pad "1" smd circle
			(at -0.40005 0 180)
			(size 0 0)
			(layers "F.Cu" "F.Mask" "F.Paste")
			(net "P0V8_PEX2_VR_CONFIG")
		)
		(pad "2" smd circle
			(at 0.40005 0 180)
			(size 0 0)
			(layers "F.Cu" "F.Mask" "F.Paste")
			(net "GND")
		)
	)
	(footprint ""
		(layer "F.Cu")
		(at 254.84709 -54.3941)
		(property "Reference" "PU38"
			(at -2.074418 3.195574 0)
			(unlocked yes)
			(layer "F.SilkS")
			(effects
				(font
					(size 0.7874 0.5842)
					(thickness 0.1524)
				)
				(justify left)
			)
		)
		(property "Value" ""
			(at 0 0 0)
			(layer "F.Fab")
			(effects
				(font
					(size 1.27 1.27)
				)
			)
		)
		(duplicate_pad_numbers_are_jumpers no)
		(fp_line
			(start -1.943608 -1.549908)
			(end 1.943608 -1.549908)
			(stroke
				(width 0.1524)
				(type default)
			)
			(layer "F.SilkS")
		)
		(fp_line
			(start -1.943608 1.549908)
			(end -1.943608 -1.549908)
			(stroke
				(width 0.1524)
				(type default)
			)
			(layer "F.SilkS")
		)
		(fp_line
			(start 1.943608 -1.549908)
			(end 1.943608 1.549908)
			(stroke
				(width 0.1524)
				(type default)
			)
			(layer "F.SilkS")
		)
		(fp_line
			(start 1.943608 1.549908)
			(end -1.943608 1.549908)
			(stroke
				(width 0.1524)
				(type default)
			)
			(layer "F.SilkS")
		)
		(fp_poly
			(pts
				(xy -2.019808 -1.549908) (xy -1.257808 -1.549908) (xy -1.257808 -1.880108) (xy -2.019808 -1.880108)
			)
			(stroke
				(width 0)
				(type default)
			)
			(fill yes)
			(layer "F.SilkS")
		)
		(fp_line
			(start -1.549908 -1.549908)
			(end 1.549908 -1.549908)
			(stroke
				(width 0.1)
				(type default)
			)
			(layer "F.Fab")
		)
		(fp_line
			(start -1.549908 1.549908)
			(end -1.549908 -1.549908)
			(stroke
				(width 0.1)
				(type default)
			)
			(layer "F.Fab")
		)
		(fp_line
			(start 1.549908 -1.549908)
			(end 1.549908 1.549908)
			(stroke
				(width 0.1)
				(type default)
			)
			(layer "F.Fab")
		)
		(fp_line
			(start 1.549908 1.549908)
			(end -1.549908 1.549908)
			(stroke
				(width 0.1)
				(type default)
			)
			(layer "F.Fab")
		)
		(fp_poly
			(pts
				(xy -2.019808 -1.549908) (xy -1.257808 -1.549908) (xy -1.257808 -1.880108) (xy -2.019808 -1.880108)
			)
			(stroke
				(width 0)
				(type default)
			)
			(fill yes)
			(layer "F.Fab")
		)
		(pad "1" smd rect
			(at -1.500124 -1.249934 270)
			(size 0.2794 0.6096)
			(layers "F.Cu" "F.Mask" "F.Paste")
			(net "P12V_SSD8_R")
		)
		(pad "2" smd rect
			(at -1.500124 -0.750062 270)
			(size 0.2794 0.6096)
			(layers "F.Cu" "F.Mask" "F.Paste")
			(net "P12V_SSD8_R")
		)
		(pad "3" smd rect
			(at -1.500124 -0.249936 270)
			(size 0.2794 0.6096)
			(layers "F.Cu" "F.Mask" "F.Paste")
			(net "P12V_SSD8_R")
		)
		(pad "4" smd rect
			(at -1.500124 0.249936 270)
			(size 0.2794 0.6096)
			(layers "F.Cu" "F.Mask" "F.Paste")
			(net "P12V_SSD8_R")
		)
		(pad "5" smd rect
			(at -1.500124 0.750062 270)
			(size 0.2794 0.6096)
			(layers "F.Cu" "F.Mask" "F.Paste")
			(net "P12V_SSD8_R")
		)
		(pad "6" smd rect
			(at -1.500124 1.249934 270)
			(size 0.2794 0.6096)
			(layers "F.Cu" "F.Mask" "F.Paste")
			(net "GND")
		)
		(pad "7" smd rect
			(at 1.500124 1.249934 270)
			(size 0.2794 0.6096)
			(layers "F.Cu" "F.Mask" "F.Paste")
			(net "P12V_SSD8_SS")
		)
		(pad "8" smd rect
			(at 1.500124 0.750062 270)
			(size 0.2794 0.6096)
			(layers "F.Cu" "F.Mask" "F.Paste")
			(net "PWRGD_P12V_SSD8")
		)
		(pad "9" smd rect
			(at 1.500124 0.249936 270)
			(size 0.2794 0.6096)
			(layers "F.Cu" "F.Mask" "F.Paste")
			(net "P12V_SSD8_OCP")
		)
		(pad "10" smd rect
			(at 1.500124 -0.249936 270)
			(size 0.2794 0.6096)
			(layers "F.Cu" "F.Mask" "F.Paste")
			(net "P5V_AUX")
		)
		(pad "11" smd rect
			(at 1.500124 -0.750062 270)
			(size 0.2794 0.6096)
			(layers "F.Cu" "F.Mask" "F.Paste")
			(net "SSD8_PWR_EN_R")
		)
		(pad "12" smd rect
			(at 1.500124 -1.249934 270)
			(size 0.2794 0.6096)
			(layers "F.Cu" "F.Mask" "F.Paste")
			(net "P12V_AUX")
		)
		(pad "13" smd rect
			(at 0 0)
			(size 1.9812 2.7178)
			(layers "F.Cu" "F.Mask" "F.Paste")
			(net "P12V_AUX")
		)
		(zone
			(layer "F.Cu")
			(hatch none 0.5)
			(connect_pads
				(clearance 0)
			)
			(min_thickness 0.25)
			(keepout
				(tracks not_allowed)
				(vias allowed)
				(pads allowed)
				(copperpour not_allowed)
				(footprints allowed)
			)
			(placement
				(enabled no)
				(sheetname "")
			)
			(fill
				(thermal_gap 0.5)
				(thermal_bridge_width 0.5)
				(island_removal_mode 0)
			)
			(polygon
				(pts
					(xy 255.99009 -55.9435) (xy 255.99009 -55.8165) (xy 255.99009 -52.8447) (xy 255.99009 -52.844192)
					(xy 253.70409 -52.844192) (xy 253.70409 -52.8447) (xy 253.70409 -52.9717) (xy 253.70409 -54.3941)
					(xy 253.80569 -54.3941) (xy 253.80569 -52.9717) (xy 255.88849 -52.9717) (xy 255.88849 -55.8165)
					(xy 253.80569 -55.8165) (xy 253.80569 -54.4195) (xy 253.70409 -54.4195) (xy 253.70409 -55.8165)
					(xy 253.70409 -55.9435) (xy 253.70409 -55.944008) (xy 255.99009 -55.944008)
				)
			)
		)
	)
	(footprint ""
		(layer "F.Cu")
		(at 83.394042 -29.507688 -90)
		(property "Reference" "PC683"
			(at 0 0 270)
			(layer "F.SilkS")
			(hide yes)
			(effects
				(font
					(size 1.27 1.27)
				)
			)
		)
		(property "Value" ""
			(at 0 0 270)
			(layer "F.Fab")
			(effects
				(font
					(size 1.27 1.27)
				)
			)
		)
		(duplicate_pad_numbers_are_jumpers no)
		(fp_line
			(start -1.524 0.762)
			(end -1.524 -0.762)
			(stroke
				(width 0.1524)
				(type default)
			)
			(layer "F.SilkS")
		)
		(fp_line
			(start 1.524 0.762)
			(end -1.524 0.762)
			(stroke
				(width 0.1524)
				(type default)
			)
			(layer "F.SilkS")
		)
		(fp_line
			(start -1.524 -0.762)
			(end 1.524 -0.762)
			(stroke
				(width 0.1524)
				(type default)
			)
			(layer "F.SilkS")
		)
		(fp_line
			(start 1.524 -0.762)
			(end 1.524 0.762)
			(stroke
				(width 0.1524)
				(type default)
			)
			(layer "F.SilkS")
		)
		(fp_line
			(start -1.1049 0.724916)
			(end 1.1049 0.724916)
			(stroke
				(width 0.1)
				(type default)
			)
			(layer "F.Fab")
		)
		(fp_line
			(start 1.1049 0.724916)
			(end 1.1049 -0.724916)
			(stroke
				(width 0.1)
				(type default)
			)
			(layer "F.Fab")
		)
		(fp_line
			(start -1.1049 -0.724916)
			(end -1.1049 0.724916)
			(stroke
				(width 0.1)
				(type default)
			)
			(layer "F.Fab")
		)
		(fp_line
			(start 1.1049 -0.724916)
			(end -1.1049 -0.724916)
			(stroke
				(width 0.1)
				(type default)
			)
			(layer "F.Fab")
		)
		(pad "1" smd rect
			(at -0.889 0 90)
			(size 1.016 1.27)
			(layers "F.Cu" "F.Mask" "F.Paste")
			(net "P3V3_SSD3")
		)
		(pad "2" smd rect
			(at 0.889 0 90)
			(size 1.016 1.27)
			(layers "F.Cu" "F.Mask" "F.Paste")
			(net "GND")
		)
	)
	(footprint ""
		(layer "F.Cu")
		(at 336.004662 -10.545572 90)
		(property "Reference" "R1706"
			(at 0 0 90)
			(layer "F.SilkS")
			(hide yes)
			(effects
				(font
					(size 1.27 1.27)
				)
			)
		)
		(property "Value" ""
			(at 0 0 90)
			(layer "F.Fab")
			(effects
				(font
					(size 1.27 1.27)
				)
			)
		)
		(duplicate_pad_numbers_are_jumpers no)
		(fp_line
			(start 0.7874 -0.4064)
			(end 0.7874 0.4064)
			(stroke
				(width 0.1524)
				(type default)
			)
			(layer "F.SilkS")
		)
		(fp_line
			(start -0.7874 -0.4064)
			(end 0.7874 -0.4064)
			(stroke
				(width 0.1524)
				(type default)
			)
			(layer "F.SilkS")
		)
		(fp_line
			(start 0.7874 0.4064)
			(end -0.7874 0.4064)
			(stroke
				(width 0.1524)
				(type default)
			)
			(layer "F.SilkS")
		)
		(fp_line
			(start -0.7874 0.4064)
			(end -0.7874 -0.4064)
			(stroke
				(width 0.1524)
				(type default)
			)
			(layer "F.SilkS")
		)
		(fp_line
			(start -0.12065 -0.305054)
			(end -0.12065 -0.2794)
			(stroke
				(width 0.1)
				(type default)
			)
			(layer "F.Fab")
		)
		(fp_line
			(start -0.67945 -0.305054)
			(end -0.12065 -0.305054)
			(stroke
				(width 0.1)
				(type default)
			)
			(layer "F.Fab")
		)
		(fp_line
			(start 0.67945 -0.3048)
			(end 0.67945 0.3048)
			(stroke
				(width 0.1)
				(type default)
			)
			(layer "F.Fab")
		)
		(fp_line
			(start 0.12065 -0.3048)
			(end 0.67945 -0.3048)
			(stroke
				(width 0.1)
				(type default)
			)
			(layer "F.Fab")
		)
		(fp_line
			(start 0.12065 -0.2794)
			(end 0.12065 -0.3048)
			(stroke
				(width 0.1)
				(type default)
			)
			(layer "F.Fab")
		)
		(fp_line
			(start -0.12065 -0.2794)
			(end 0.12065 -0.2794)
			(stroke
				(width 0.1)
				(type default)
			)
			(layer "F.Fab")
		)
		(fp_line
			(start 0.120396 0.2794)
			(end -0.12065 0.2794)
			(stroke
				(width 0.1)
				(type default)
			)
			(layer "F.Fab")
		)
		(fp_line
			(start -0.12065 0.2794)
			(end -0.12065 0.3048)
			(stroke
				(width 0.1)
				(type default)
			)
			(layer "F.Fab")
		)
		(fp_line
			(start 0.67945 0.3048)
			(end 0.120396 0.3048)
			(stroke
				(width 0.1)
				(type default)
			)
			(layer "F.Fab")
		)
		(fp_line
			(start 0.120396 0.3048)
			(end 0.120396 0.2794)
			(stroke
				(width 0.1)
				(type default)
			)
			(layer "F.Fab")
		)
		(fp_line
			(start -0.12065 0.3048)
			(end -0.67945 0.3048)
			(stroke
				(width 0.1)
				(type default)
			)
			(layer "F.Fab")
		)
		(fp_line
			(start -0.67945 0.3048)
			(end -0.67945 -0.305054)
			(stroke
				(width 0.1)
				(type default)
			)
			(layer "F.Fab")
		)
		(pad "1" smd circle
			(at -0.40005 0 90)
			(size 0 0)
			(layers "F.Cu" "F.Mask" "F.Paste")
			(net "P3V3_SSD11")
		)
		(pad "2" smd circle
			(at 0.40005 0 90)
			(size 0 0)
			(layers "F.Cu" "F.Mask" "F.Paste")
			(net "SMB_ISO_SSD11_SDA")
		)
	)
	(footprint ""
		(layer "F.Cu")
		(at 115.356386 -84.469986 180)
		(property "Reference" "R1144"
			(at 0 0 180)
			(layer "F.SilkS")
			(hide yes)
			(effects
				(font
					(size 1.27 1.27)
				)
			)
		)
		(property "Value" ""
			(at 0 0 180)
			(layer "F.Fab")
			(effects
				(font
					(size 1.27 1.27)
				)
			)
		)
		(duplicate_pad_numbers_are_jumpers no)
		(fp_line
			(start -0.7874 -0.4064)
			(end 0.7874 -0.4064)
			(stroke
				(width 0.1524)
				(type default)
			)
			(layer "F.SilkS")
		)
		(fp_line
			(start 0.67945 0.3048)
			(end 0.120396 0.3048)
			(stroke
				(width 0.1)
				(type default)
			)
			(layer "F.Fab")
		)
		(fp_line
			(start 0.67945 -0.3048)
			(end 0.67945 0.3048)
			(stroke
				(width 0.1)
				(type default)
			)
			(layer "F.Fab")
		)
		(fp_line
			(start 0.12065 -0.2794)
			(end 0.12065 -0.3048)
			(stroke
				(width 0.1)
				(type default)
			)
			(layer "F.Fab")
		)
		(fp_line
			(start 0.12065 -0.3048)
			(end 0.67945 -0.3048)
			(stroke
				(width 0.1)
				(type default)
			)
			(layer "F.Fab")
		)
		(fp_line
			(start 0.120396 0.3048)
			(end 0.120396 0.2794)
			(stroke
				(width 0.1)
				(type default)
			)
			(layer "F.Fab")
		)
		(fp_line
			(start 0.120396 0.2794)
			(end -0.12065 0.2794)
			(stroke
				(width 0.1)
				(type default)
			)
			(layer "F.Fab")
		)
		(fp_line
			(start -0.12065 0.3048)
			(end -0.67945 0.3048)
			(stroke
				(width 0.1)
				(type default)
			)
			(layer "F.Fab")
		)
		(fp_line
			(start -0.12065 0.2794)
			(end -0.12065 0.3048)
			(stroke
				(width 0.1)
				(type default)
			)
			(layer "F.Fab")
		)
		(fp_line
			(start -0.12065 -0.2794)
			(end 0.12065 -0.2794)
			(stroke
				(width 0.1)
				(type default)
			)
			(layer "F.Fab")
		)
		(fp_line
			(start -0.12065 -0.305054)
			(end -0.12065 -0.2794)
			(stroke
				(width 0.1)
				(type default)
			)
			(layer "F.Fab")
		)
		(fp_line
			(start -0.67945 0.3048)
			(end -0.67945 -0.305054)
			(stroke
				(width 0.1)
				(type default)
			)
			(layer "F.Fab")
		)
		(fp_line
			(start -0.67945 -0.305054)
			(end -0.12065 -0.305054)
			(stroke
				(width 0.1)
				(type default)
			)
			(layer "F.Fab")
		)
		(pad "1" smd circle
			(at -0.40005 0 180)
			(size 0 0)
			(layers "F.Cu" "F.Mask" "F.Paste")
			(net "CLK_100M_DB800ZL_SSD4_R_DP")
		)
		(pad "2" smd circle
			(at 0.40005 0 180)
			(size 0 0)
			(layers "F.Cu" "F.Mask" "F.Paste")
			(net "CLK_100M_DB800ZL_SSD4_DP")
		)
	)
)
